# BASEBOARD_FAB2 (Tioga Pass) — schematic netlist excerpt (pin names and nets, part order shuffled) for the footprints in the layout excerpt that follows; sources: Cadence DE-HDL packaged netlist, KiCad conversion of Wiwynn_Tioga_Pass_MB.brd

J4G1  SCONN288_H44441004  SCONN  pkg PIP  page 43
  \12v\(1)  = P12V_NVDIMM_ABC
  VSS(93)  = GND
  DQ(4)  = M_A_DQ<5>
  VSS(92)  = GND
  DQ(0)  = M_A_DQ<1>
  VSS(91)  = GND
  DQS9P  = M_A_DQS_DP<9>
  DQS9N  = M_A_DQS_DN<9>
  VSS(90)  = GND
  DQ(6)  = M_A_DQ<7>
  VSS(89)  = GND
  DQ(2)  = M_A_DQ<3>
  VSS(88)  = GND
  DQ(12)  = M_A_DQ<13>
  VSS(87)  = GND
  DQ(8)  = M_A_DQ<9>
  VSS(86)  = GND
  DQS10P  = M_A_DQS_DP<10>
  DQS10N  = M_A_DQS_DN<10>
  VSS(85)  = GND
  DQ(14)  = M_A_DQ<15>
  VSS(84)  = GND
  DQ(10)  = M_A_DQ<11>
  VSS(83)  = GND
  DQ(20)  = M_A_DQ<21>
  VSS(82)  = GND
  DQ(16)  = M_A_DQ<17>
  VSS(81)  = GND
  DQS11P  = M_A_DQS_DP<11>
  DQS11N  = M_A_DQS_DN<11>
  VSS(80)  = GND
  DQ(22)  = M_A_DQ<23>
  VSS(79)  = GND
  DQ(18)  = M_A_DQ<19>
  VSS(78)  = GND
  DQ(28)  = M_A_DQ<29>
  VSS(77)  = GND
  DQ(24)  = M_A_DQ<25>
  VSS(76)  = GND
  DQS12P  = M_A_DQS_DP<12>
  DQS12N  = M_A_DQS_DN<12>
  VSS(75)  = GND
  DQ(30)  = M_A_DQ<31>
  VSS(74)  = GND
  DQ(26)  = M_A_DQ<27>
  VSS(73)  = GND
  CB(4)  = M_A_ECC<5>
  VSS(72)  = GND
  CB(0)  = M_A_ECC<1>
  VSS(71)  = GND
  DQS17P  = M_A_DQS_DP<17>
  DQS17N  = M_A_DQS_DN<17>
  VSS(70)  = GND
  CB(6)  = M_A_ECC<7>
  VSS(69)  = GND
  CB(2)  = M_A_ECC<3>
  VSS(68)  = GND
  RESET_N  = M_ABC_RST_N
  VDD(25)  = PVDDQ_ABC
  CKE(0)  = M_A_CKE<0>
  VDD(24)  = PVDDQ_ABC
  ACT_N  = M_A_ACT_N
  BG(0)  = M_A_BG<0>
  VDD(23)  = PVDDQ_ABC
  A12  = M_A_MA<12>
  A9  = M_A_MA<9>
  VDD(22)  = PVDDQ_ABC
  A8  = M_A_MA<8>
  A6  = M_A_MA<6>
  VDD(21)  = PVDDQ_ABC
  A3  = M_A_MA<3>
  A1  = M_A_MA<1>
  VDD(20)  = PVDDQ_ABC
  CK0P  = M_A_CLK_DP<0>
  CK0N  = M_A_CLK_DN<0>
  VDD(19)  = PVDDQ_ABC
  VTT(1)  = PVTT_ABC
  EVENT_N  = FM_DIMM_EVENT_COD_N
  A0  = M_A_MA<0>
  VDD(18)  = PVDDQ_ABC
  BA(0)  = M_A_BA<0>
  A16_RAS_N  = M_A_MA<16>
  VDD(17)  = PVDDQ_ABC
  S0_N  = M_A_CS_N<0>
  VDD(16)  = PVDDQ_ABC
  A15_CAS_N  = M_A_MA<15>
  ODT(0)  = M_A_ODT<0>
  VDD(15)  = PVDDQ_ABC
  S1_N  = M_A_CS_N<1>
  VDD(14)  = PVDDQ_ABC
  ODT(1)  = M_A_ODT<1>
  VDD(13)  = PVDDQ_ABC
  S2_N_C(0)  = M_A_CS_N<2>
  VSS(67)  = GND
  DQ(36)  = M_A_DQ<37>
  VSS(66)  = GND
  DQ(32)  = M_A_DQ<33>
  VSS(65)  = GND
  DQS13P  = M_A_DQS_DP<13>
  DQS13N  = M_A_DQS_DN<13>
  VSS(64)  = GND
  DQ(38)  = M_A_DQ<39>
  VSS(63)  = GND
  DQ(34)  = M_A_DQ<35>
  VSS(62)  = GND
  DQ(44)  = M_A_DQ<45>
  VSS(61)  = GND
  DQ(40)  = M_A_DQ<41>
  VSS(60)  = GND
  DQS14P  = M_A_DQS_DP<14>
  DQS14N  = M_A_DQS_DN<14>
  VSS(59)  = GND
  DQ(46)  = M_A_DQ<47>
  VSS(58)  = GND
  DQ(42)  = M_A_DQ<43>
  VSS(57)  = GND
  DQ(52)  = M_A_DQ<53>
  VSS(56)  = GND
  DQ(48)  = M_A_DQ<49>
  VSS(55)  = GND
  DQS15P  = M_A_DQS_DP<15>
  DQS15N  = M_A_DQS_DN<15>
  VSS(54)  = GND
  DQ(54)  = M_A_DQ<55>
  VSS(53)  = GND
  DQ(50)  = M_A_DQ<51>
  VSS(52)  = GND
  DQ(60)  = M_A_DQ<61>
  VSS(51)  = GND
  DQ(56)  = M_A_DQ<57>
  VSS(50)  = GND
  DQS16P  = M_A_DQS_DP<16>
  DQS16N  = M_A_DQS_DN<16>
  VSS(49)  = GND
  DQ(62)  = M_A_DQ<63>
  VSS(48)  = GND
  DQ(58)  = M_A_DQ<59>
  VSS(47)  = GND
  SA(0)  = GND
  SA(1)  = GND
  SCL  = SMB_DDR_ABC_VPP_SCL
  VPP(4)  = PVPP_ABC
  VPP(3)  = PVPP_ABC
  RFU(2)  = TP_CH_A_DIMM_A0_RFU_2
  \12v\(0)  = P12V_NVDIMM_ABC
  VREFCA  = M_A_VREF
  VSS(46)  = GND
  DQ(5)  = M_A_DQ<4>
  VSS(45)  = GND
  DQ(1)  = M_A_DQ<0>
  VSS(44)  = GND
  DQS0N  = M_A_DQS_DN<0>
  DQS0P  = M_A_DQS_DP<0>
  VSS(43)  = GND
  DQ(7)  = M_A_DQ<6>
  VSS(42)  = GND
  DQ(3)  = M_A_DQ<2>
  VSS(41)  = GND
  DQ(13)  = M_A_DQ<12>
  VSS(40)  = GND
  DQ(9)  = M_A_DQ<8>
  VSS(39)  = GND
  DQS1N  = M_A_DQS_DN<1>
  DQS1P  = M_A_DQS_DP<1>
  VSS(38)  = GND
  DQ(15)  = M_A_DQ<14>
  VSS(37)  = GND
  DQ(11)  = M_A_DQ<10>
  VSS(36)  = GND
  DQ(21)  = M_A_DQ<20>
  VSS(35)  = GND
  DQ(17)  = M_A_DQ<16>
  VSS(34)  = GND
  DQS2N  = M_A_DQS_DN<2>
  DQS2P  = M_A_DQS_DP<2>
  VSS(33)  = GND
  DQ(23)  = M_A_DQ<22>
  VSS(32)  = GND
  DQ(19)  = M_A_DQ<18>
  VSS(31)  = GND
  DQ(29)  = M_A_DQ<28>
  VSS(30)  = GND
  DQ(25)  = M_A_DQ<24>
  VSS(29)  = GND
  DQS3N  = M_A_DQS_DN<3>
  DQS3P  = M_A_DQS_DP<3>
  VSS(28)  = GND
  DQ(31)  = M_A_DQ<30>
  VSS(27)  = GND
  DQ(27)  = M_A_DQ<26>
  VSS(26)  = GND
  CB(5)  = M_A_ECC<4>
  VSS(25)  = GND
  CB(1)  = M_A_ECC<0>
  VSS(24)  = GND
  DQS8N  = M_A_DQS_DN<8>
  DQS8P  = M_A_DQS_DP<8>
  VSS(23)  = GND
  CB(7)  = M_A_ECC<6>
  VSS(22)  = GND
  CB(3)  = M_A_ECC<2>
  VSS(21)  = GND
  CKE(1)  = M_A_CKE<1>
  VDD(12)  = PVDDQ_ABC
  RFU(0)  = TP_CH_A_DIMM_A0_RFU_0
  VDD(11)  = PVDDQ_ABC
  BG(1)  = M_A_BG<1>
  ALERT_N  = M_A_ALERT_N
  VDD(10)  = PVDDQ_ABC
  A11  = M_A_MA<11>
  A7  = M_A_MA<7>
  VDD(9)  = PVDDQ_ABC
  A5  = M_A_MA<5>
  A4  = M_A_MA<4>
  VDD(8)  = PVDDQ_ABC
  A2  = M_A_MA<2>
  VDD(7)  = PVDDQ_ABC
  CK1P  = M_A_CLK_DP<1>
  CK1N  = M_A_CLK_DN<1>
  VDD(6)  = PVDDQ_ABC
  VTT(0)  = PVTT_ABC
  PAR  = M_A_PAR
  VDD(5)  = PVDDQ_ABC
  BA(1)  = M_A_BA<1>
  A10  = M_A_MA<10>
  VDD(4)  = PVDDQ_ABC
  RFU(1)  = TP_CH_A_DIMM_A0_RFU_1
  A14_WE_N  = M_A_MA<14>
  VDD(3)  = PVDDQ_ABC
  SAVE_N_NC  = FM_ADR_COMPLETE_ABC_N
  VDD(2)  = PVDDQ_ABC
  A13  = M_A_MA<13>
  VDD(1)  = PVDDQ_ABC
  A17  = M_A_MA<17>
  C(2)  = M_A_C<2>
  VDD(0)  = PVDDQ_ABC
  S3_N_C(1)  = M_A_CS_N<3>
  SA(2)  = GND
  VSS(20)  = GND
  DQ(37)  = M_A_DQ<36>
  VSS(19)  = GND
  DQ(33)  = M_A_DQ<32>
  VSS(18)  = GND
  DQS4N  = M_A_DQS_DN<4>
  DQS4P  = M_A_DQS_DP<4>
  VSS(17)  = GND
  DQ(39)  = M_A_DQ<38>
  VSS(16)  = GND
  DQ(35)  = M_A_DQ<34>
  VSS(15)  = GND
  DQ(45)  = M_A_DQ<44>
  VSS(14)  = GND
  DQ(41)  = M_A_DQ<40>
  VSS(13)  = GND
  DQS5N  = M_A_DQS_DN<5>
  DQS5P  = M_A_DQS_DP<5>
  VSS(12)  = GND
  DQ(47)  = M_A_DQ<46>
  VSS(11)  = GND
  DQ(43)  = M_A_DQ<42>
  VSS(10)  = GND
  DQ(53)  = M_A_DQ<52>
  VSS(9)  = GND
  DQ(49)  = M_A_DQ<48>
  VSS(8)  = GND
  DQS6N  = M_A_DQS_DN<6>
  DQS6P  = M_A_DQS_DP<6>
  VSS(7)  = GND
  DQ(55)  = M_A_DQ<54>
  VSS(6)  = GND
  DQ(51)  = M_A_DQ<50>
  VSS(5)  = GND
  DQ(61)  = M_A_DQ<60>
  VSS(4)  = GND
  DQ(57)  = M_A_DQ<56>
  VSS(3)  = GND
  DQS7N  = M_A_DQS_DN<7>
  DQS7P  = M_A_DQS_DP<7>
  VSS(2)  = GND
  DQ(63)  = M_A_DQ<62>
  VSS(1)  = GND
  DQ(59)  = M_A_DQ<58>
  VSS(0)  = GND
  VDDSPD  = PVPP_ABC
  SDA  = SMB_DDR_ABC_VPP_SDA
  VPP(1)  = PVPP_ABC
  VPP(0)  = PVPP_ABC
  VPP(2)  = PVPP_ABC

(kicad_pcb
	(version 20260206)
	(generator "pcbnew")
	(generator_version "10.0")
	(general
		(thickness 1.6)
		(legacy_teardrops no)
	)
	(paper "A4")
	(title_block
		(title "Wiwynn_Tioga_Pass_MB.brd")
		(comment 1 "Tioga Pass / footprint 2167 of 4770 (J4G1), pads 1-51 of 291")
	)
	(layers
		(0 "F.Cu" signal "TOP")
		(4 "In1.Cu" signal "L2GND")
		(6 "In2.Cu" signal "L3")
		(8 "In3.Cu" signal "L4GND")
		(10 "In4.Cu" signal "L5")
		(12 "In5.Cu" signal "L6GND")
		(14 "In6.Cu" signal "L7VCC")
		(16 "In7.Cu" signal "L8VCC")
		(18 "In8.Cu" signal "L9GND")
		(20 "In9.Cu" signal "L10")
		(22 "In10.Cu" signal "L11GND")
		(24 "In11.Cu" signal "L12")
		(26 "In12.Cu" signal "L13GND")
		(2 "B.Cu" signal "BOTTOM")
		(9 "F.Adhes" user "F.Adhesive")
		(11 "B.Adhes" user "B.Adhesive")
		(13 "F.Paste" user "Package Geometry/Pastemask Top")
		(15 "B.Paste" user "Package Geometry/Pastemask Bottom")
		(5 "F.SilkS" user "Ref Des/Silkscreen Top")
		(7 "B.SilkS" user "Ref Des/Silkscreen Bottom")
		(1 "F.Mask" user "Board Geometry/Soldermask Top")
		(3 "B.Mask" user "Board Geometry/Soldermask Bottom")
		(17 "Dwgs.User" user "User.Drawings")
		(19 "Cmts.User" user "User.Comments")
		(21 "Eco1.User" user "User.Eco1")
		(23 "Eco2.User" user "User.Eco2")
		(25 "Edge.Cuts" user "Board Geometry/Outline")
		(27 "Margin" user)
		(31 "F.CrtYd" user "Package Geometry/Place Bound Top")
		(29 "B.CrtYd" user "Package Geometry/Place Bound Bottom")
		(35 "F.Fab" user "Ref Des/Assembly Top")
		(33 "B.Fab" user "Ref Des/Assembly Bottom")
	)
	(footprint ""
		(layer "F.Cu")
		(at 194.700398 -15.423642 90)
		(property "Reference" "J4G1"
			(at 9.060688 37.32911 0)
			(unlocked yes)
			(layer "F.SilkS")
			(effects
				(font
					(size 0.7874 0.5842)
					(thickness 0.1524)
				)
				(justify left)
			)
		)
		(property "Value" ""
			(at 0 0 90)
			(layer "F.Fab")
			(effects
				(font
					(size 1.27 1.27)
				)
			)
		)
		(duplicate_pad_numbers_are_jumpers no)
		(pad "" thru_hole circle
			(at 2.29997 -5.649976 90)
			(size 2.8194 2.8194)
			(drill 2.4384)
			(layers "*.Cu" "*.Mask")
			(remove_unused_layers no)
			(clearance 0.127)
			(thermal_gap 0.127)
		)
		(pad "" thru_hole oval
			(at 2.29997 68.90004 90)
			(size 2.8194 1.5748)
			(drill oval 2.4384 1.1938)
			(layers "*.Cu" "*.Mask")
			(remove_unused_layers no)
			(clearance 0.127)
			(thermal_gap 0.127)
		)
		(pad "" thru_hole circle
			(at 2.29997 132.299964 90)
			(size 2.8194 2.8194)
			(drill 2.4384)
			(layers "*.Cu" "*.Mask")
			(remove_unused_layers no)
			(clearance 0.127)
			(thermal_gap 0.127)
		)
		(pad "1" smd rect
			(at 0 0 90)
			(size 1.8034 0.508)
			(layers "F.Cu" "F.Mask" "F.Paste")
			(net "P12V_NVDIMM_ABC")
		)
		(pad "2" smd rect
			(at 0 0.849884 90)
			(size 1.8034 0.508)
			(layers "F.Cu" "F.Mask" "F.Paste")
			(net "GND")
		)
		(pad "3" smd rect
			(at 0 1.700022 90)
			(size 1.8034 0.508)
			(layers "F.Cu" "F.Mask" "F.Paste")
			(net "M_A_DQ<5>")
		)
		(pad "4" smd rect
			(at 0 2.549906 90)
			(size 1.8034 0.508)
			(layers "F.Cu" "F.Mask" "F.Paste")
			(net "GND")
		)
		(pad "5" smd rect
			(at 0 3.400044 90)
			(size 1.8034 0.508)
			(layers "F.Cu" "F.Mask" "F.Paste")
			(net "M_A_DQ<1>")
		)
		(pad "6" smd rect
			(at 0 4.249928 90)
			(size 1.8034 0.508)
			(layers "F.Cu" "F.Mask" "F.Paste")
			(net "GND")
		)
		(pad "7" smd rect
			(at 0 5.100066 90)
			(size 1.8034 0.508)
			(layers "F.Cu" "F.Mask" "F.Paste")
			(net "M_A_DQS_DP<9>")
		)
		(pad "8" smd rect
			(at 0 5.94995 90)
			(size 1.8034 0.508)
			(layers "F.Cu" "F.Mask" "F.Paste")
			(net "M_A_DQS_DN<9>")
		)
		(pad "9" smd rect
			(at 0 6.800088 90)
			(size 1.8034 0.508)
			(layers "F.Cu" "F.Mask" "F.Paste")
			(net "GND")
		)
		(pad "10" smd rect
			(at 0 7.649972 90)
			(size 1.8034 0.508)
			(layers "F.Cu" "F.Mask" "F.Paste")
			(net "M_A_DQ<7>")
		)
		(pad "11" smd rect
			(at 0 8.50011 90)
			(size 1.8034 0.508)
			(layers "F.Cu" "F.Mask" "F.Paste")
			(net "GND")
		)
		(pad "12" smd rect
			(at 0 9.349994 90)
			(size 1.8034 0.508)
			(layers "F.Cu" "F.Mask" "F.Paste")
			(net "M_A_DQ<3>")
		)
		(pad "13" smd rect
			(at 0 10.199878 90)
			(size 1.8034 0.508)
			(layers "F.Cu" "F.Mask" "F.Paste")
			(net "GND")
		)
		(pad "14" smd rect
			(at 0 11.050016 90)
			(size 1.8034 0.508)
			(layers "F.Cu" "F.Mask" "F.Paste")
			(net "M_A_DQ<13>")
		)
		(pad "15" smd rect
			(at 0 11.8999 90)
			(size 1.8034 0.508)
			(layers "F.Cu" "F.Mask" "F.Paste")
			(net "GND")
		)
		(pad "16" smd rect
			(at 0 12.750038 90)
			(size 1.8034 0.508)
			(layers "F.Cu" "F.Mask" "F.Paste")
			(net "M_A_DQ<9>")
		)
		(pad "17" smd rect
			(at 0 13.599922 90)
			(size 1.8034 0.508)
			(layers "F.Cu" "F.Mask" "F.Paste")
			(net "GND")
		)
		(pad "18" smd rect
			(at 0 14.45006 90)
			(size 1.8034 0.508)
			(layers "F.Cu" "F.Mask" "F.Paste")
			(net "M_A_DQS_DP<10>")
		)
		(pad "19" smd rect
			(at 0 15.299944 90)
			(size 1.8034 0.508)
			(layers "F.Cu" "F.Mask" "F.Paste")
			(net "M_A_DQS_DN<10>")
		)
		(pad "20" smd rect
			(at 0 16.150082 90)
			(size 1.8034 0.508)
			(layers "F.Cu" "F.Mask" "F.Paste")
			(net "GND")
		)
		(pad "21" smd rect
			(at 0 16.999966 90)
			(size 1.8034 0.508)
			(layers "F.Cu" "F.Mask" "F.Paste")
			(net "M_A_DQ<15>")
		)
		(pad "22" smd rect
			(at 0 17.850104 90)
			(size 1.8034 0.508)
			(layers "F.Cu" "F.Mask" "F.Paste")
			(net "GND")
		)
		(pad "23" smd rect
			(at 0 18.699988 90)
			(size 1.8034 0.508)
			(layers "F.Cu" "F.Mask" "F.Paste")
			(net "M_A_DQ<11>")
		)
		(pad "24" smd rect
			(at 0 19.550126 90)
			(size 1.8034 0.508)
			(layers "F.Cu" "F.Mask" "F.Paste")
			(net "GND")
		)
		(pad "25" smd rect
			(at 0 20.40001 90)
			(size 1.8034 0.508)
			(layers "F.Cu" "F.Mask" "F.Paste")
			(net "M_A_DQ<21>")
		)
		(pad "26" smd rect
			(at 0 21.249894 90)
			(size 1.8034 0.508)
			(layers "F.Cu" "F.Mask" "F.Paste")
			(net "GND")
		)
		(pad "27" smd rect
			(at 0 22.100032 90)
			(size 1.8034 0.508)
			(layers "F.Cu" "F.Mask" "F.Paste")
			(net "M_A_DQ<17>")
		)
		(pad "28" smd rect
			(at 0 22.949916 90)
			(size 1.8034 0.508)
			(layers "F.Cu" "F.Mask" "F.Paste")
			(net "GND")
		)
		(pad "29" smd rect
			(at 0 23.800054 90)
			(size 1.8034 0.508)
			(layers "F.Cu" "F.Mask" "F.Paste")
			(net "M_A_DQS_DP<11>")
		)
		(pad "30" smd rect
			(at 0 24.649938 90)
			(size 1.8034 0.508)
			(layers "F.Cu" "F.Mask" "F.Paste")
			(net "M_A_DQS_DN<11>")
		)
		(pad "31" smd rect
			(at 0 25.500076 90)
			(size 1.8034 0.508)
			(layers "F.Cu" "F.Mask" "F.Paste")
			(net "GND")
		)
		(pad "32" smd rect
			(at 0 26.34996 90)
			(size 1.8034 0.508)
			(layers "F.Cu" "F.Mask" "F.Paste")
			(net "M_A_DQ<23>")
		)
		(pad "33" smd rect
			(at 0 27.200098 90)
			(size 1.8034 0.508)
			(layers "F.Cu" "F.Mask" "F.Paste")
			(net "GND")
		)
		(pad "34" smd rect
			(at 0 28.049982 90)
			(size 1.8034 0.508)
			(layers "F.Cu" "F.Mask" "F.Paste")
			(net "M_A_DQ<19>")
		)
		(pad "35" smd rect
			(at 0 28.90012 90)
			(size 1.8034 0.508)
			(layers "F.Cu" "F.Mask" "F.Paste")
			(net "GND")
		)
		(pad "36" smd rect
			(at 0 29.750004 90)
			(size 1.8034 0.508)
			(layers "F.Cu" "F.Mask" "F.Paste")
			(net "M_A_DQ<29>")
		)
		(pad "37" smd rect
			(at 0 30.599888 90)
			(size 1.8034 0.508)
			(layers "F.Cu" "F.Mask" "F.Paste")
			(net "GND")
		)
		(pad "38" smd rect
			(at 0 31.450026 90)
			(size 1.8034 0.508)
			(layers "F.Cu" "F.Mask" "F.Paste")
			(net "M_A_DQ<25>")
		)
		(pad "39" smd rect
			(at 0 32.29991 90)
			(size 1.8034 0.508)
			(layers "F.Cu" "F.Mask" "F.Paste")
			(net "GND")
		)
		(pad "40" smd rect
			(at 0 33.150048 90)
			(size 1.8034 0.508)
			(layers "F.Cu" "F.Mask" "F.Paste")
			(net "M_A_DQS_DP<12>")
		)
		(pad "41" smd rect
			(at 0 33.999932 90)
			(size 1.8034 0.508)
			(layers "F.Cu" "F.Mask" "F.Paste")
			(net "M_A_DQS_DN<12>")
		)
		(pad "42" smd rect
			(at 0 34.85007 90)
			(size 1.8034 0.508)
			(layers "F.Cu" "F.Mask" "F.Paste")
			(net "GND")
		)
		(pad "43" smd rect
			(at 0 35.699954 90)
			(size 1.8034 0.508)
			(layers "F.Cu" "F.Mask" "F.Paste")
			(net "M_A_DQ<31>")
		)
		(pad "44" smd rect
			(at 0 36.550092 90)
			(size 1.8034 0.508)
			(layers "F.Cu" "F.Mask" "F.Paste")
			(net "GND")
		)
		(pad "45" smd rect
			(at 0 37.399976 90)
			(size 1.8034 0.508)
			(layers "F.Cu" "F.Mask" "F.Paste")
			(net "M_A_DQ<27>")
		)
		(pad "46" smd rect
			(at 0 38.250114 90)
			(size 1.8034 0.508)
			(layers "F.Cu" "F.Mask" "F.Paste")
			(net "GND")
		)
		(pad "47" smd rect
			(at 0 39.099998 90)
			(size 1.8034 0.508)
			(layers "F.Cu" "F.Mask" "F.Paste")
			(net "M_A_ECC<5>")
		)
		(pad "48" smd rect
			(at 0 39.949882 90)
			(size 1.8034 0.508)
			(layers "F.Cu" "F.Mask" "F.Paste")
			(net "GND")
		)
	)
)
